<schema xmlns="http://www.cadence.com/spb/csschema"
	xmlns:xsi="http://www.w3.org/2001/XMLSchema-instance"
	xsi:schemaLocation="http://www.cadence.com/spb/csschema CSSchema002.xsd">
  <header>
    <schemaVersion>16.5</schemaVersion>
    <creatorTool>conceptHDL</creatorTool>
    <modifierTool>conceptHDL</modifierTool>
    <modificationTime>2011-10-11T16:01:59</modificationTime>
    <savedLibrary>mstr_symbols</savedLibrary>
  </header>
  <designs>
    <design schemaType="nameBased" name="gnd" view="sch_1">
      <lastids>
        <netid>4</netid>
      </lastids>
      <cells>
      </cells>
      <nets>
        <net>
          <id>N1</id>
          <name>a</name>
          <scope>interface</scope>
          <direction>inout</direction>
        </net>
        <net>
          <id>N2</id>
          <name>page1_a</name>
        </net>
        <net>
          <id>N4</id>
          <name>page1_gnd</name>
        </net>
        <net>
          <id>N3</id>
          <name>gnd</name>
          <scope>global</scope>
        </net>
      </nets>
      <aliases>
        <alias net1="N2" lsb1="-1" msb1="-1" net2="N1" lsb2="-1" msb2="-1" />
        <alias net1="N4" lsb1="-1" msb1="-1" net2="N2" lsb2="-1" msb2="-1" />
        <alias net1="N4" lsb1="-1" msb1="-1" net2="N3" lsb2="-1" msb2="-1" />
      </aliases>
      <differentialnets>
      </differentialnets>
      <differentialbusnets>
      </differentialbusnets>
      <netgroups>
      </netgroups>
      <netinterfaces>
      </netinterfaces>
      <instances>
      </instances>
      <templateresolutions>
      </templateresolutions>
      <templateinstances>
      </templateinstances>
      <extensions>
        <extension name="schematic_extension">
        <schematicExtension>
        <netScopes>
          <netScope ref="a">
            <pageScope number="1">
              <scope>interface</scope>
              <direction>unknown</direction>
            </pageScope>
          </netScope>
          <netScope ref="gnd">
            <pageScope number="1">
              <scope>global</scope>
            </pageScope>
          </netScope>
        </netScopes>
        <pages>
          <page number="1">
            <physicalPageNumber>1</physicalPageNumber>
            <errorStatus>false</errorStatus>
            <nets>
              <net ref="a"></net>
              <net ref="gnd"></net>
            </nets>
            <instances>
            </instances>
          </page>
        </pages>
      </schematicExtension>
        </extension>
      </extensions>
    </design>
  </designs>
</schema>
